#ISCELL
  pure_quanta quanta_title_block_c *
  *
#ISCELL
  standard offpage *
  page53_i109
#ISCELL
  standard offpage *
  page53_i110
#ISCELL
  standard offpage *
  page53_i111
#ISCELL
  standard offpage *
  page53_i112
#ISCELL
  standard offpage *
  page53_i113
#ISCELL
  standard offpage *
  page53_i114
#ISCELL
  standard offpage *
  page53_i115
#ISCELL
  standard offpage *
  page53_i116
#ISCELL
  standard tap *
  page53_i117
#ISCELL
  standard tap *
  page53_i118
#ISCELL
  standard tap *
  page53_i119
#ISCELL
  standard tap *
  page53_i120
#ISCELL
  standard tap *
  page53_i121
#ISCELL
  standard tap *
  page53_i122
#ISCELL
  standard tap *
  page53_i123
#ISCELL
  standard tap *
  page53_i124
#ISCELL
  standard tap *
  page53_i125
#ISCELL
  standard tap *
  page53_i126
#ISCELL
  standard tap *
  page53_i127
#ISCELL
  standard tap *
  page53_i128
#ISCELL
  standard tap *
  page53_i129
#ISCELL
  standard tap *
  page53_i130
#ISCELL
  standard tap *
  page53_i131
#CELL
  pure_quanta q_cap_diffbus *
  page53_i132
#CELL
  pure_quanta q_cap_diffbus *
  page53_i133
#CELL
  pure_quanta q_cap_diffbus *
  page53_i134
#CELL
  pure_quanta q_cap_diffbus *
  page53_i135
#ISCELL
  standard offpage *
  page53_i136
#ISCELL
  standard offpage *
  page53_i137
#ISCELL
  standard tap *
  page53_i138
#ISCELL
  standard offpage *
  page53_i139
#ISCELL
  standard offpage *
  page53_i140
#ISCELL
  standard offpage *
  page53_i141
#ISCELL
  standard offpage *
  page53_i142
#ISCELL
  standard offpage *
  page53_i143
#ISCELL
  standard offpage *
  page53_i144
#CELL
  pure_quanta genoa_sp5 *
  page53_i145
